# TIMECARD (Time Appliance Project (Time Card)) — schematic netlist excerpt (pin names and nets, part order shuffled) for the footprints in the layout excerpt that follows; sources: Cadence DE-HDL packaged netlist, KiCad conversion of R4006-B0001-02_R01.brd

TP187  TP_PIONT  pkg TP010CT020B030_PTH  page 25 : \1\ = IO_L24P_16
R471  RESISTOR  0OHM -  pkg SMC_0402R_H016  page 24 : \1\ = R_FT4232_I2C_SCL ; \2\ = FT4232_I2C_SCL

(kicad_pcb
	(version 20260206)
	(generator "pcbnew")
	(generator_version "10.0")
	(general
		(thickness 1.6)
		(legacy_teardrops no)
	)
	(paper "A4")
	(title_block
		(title "timecard-production-celestica-r4006 — R4006-B0001-02_R01.brd")
		(comment 1 "Time Appliance Project (Time Card) / footprints 124-125 of 1113")
	)
	(layers
		(0 "F.Cu" signal "TOP")
		(4 "In1.Cu" signal "L02_GND1")
		(6 "In2.Cu" signal "L03_SIG1")
		(8 "In3.Cu" signal "L04_GND2")
		(10 "In4.Cu" signal "L05_VCC1")
		(12 "In5.Cu" signal "L06_VCC2")
		(14 "In6.Cu" signal "L07_GND3")
		(16 "In7.Cu" signal "L08_SIG2")
		(18 "In8.Cu" signal "L09_GND4")
		(2 "B.Cu" signal "BOTTOM")
		(9 "F.Adhes" user "F.Adhesive")
		(11 "B.Adhes" user "B.Adhesive")
		(13 "F.Paste" user "Package Geometry/Pastemask Top")
		(15 "B.Paste" user "Package Geometry/Pastemask Bottom")
		(5 "F.SilkS" user "Ref Des/Silkscreen Top")
		(7 "B.SilkS" user "Ref Des/Silkscreen Bottom")
		(1 "F.Mask" user "Board Geometry/Soldermask Top")
		(3 "B.Mask" user "Board Geometry/Soldermask Bottom")
		(17 "Dwgs.User" user "User.Drawings")
		(19 "Cmts.User" user "User.Comments")
		(21 "Eco1.User" user "User.Eco1")
		(23 "Eco2.User" user "User.Eco2")
		(25 "Edge.Cuts" user "Board Geometry/Outline")
		(27 "Margin" user)
		(31 "F.CrtYd" user "Package Geometry/Place Bound Top")
		(29 "B.CrtYd" user "Package Geometry/Place Bound Bottom")
		(35 "F.Fab" user "Ref Des/Assembly Top")
		(33 "B.Fab" user "Ref Des/Assembly Bottom")
	)
	(footprint ""
		(layer "F.Cu")
		(at 18.415 -82.423 180)
		(property "Reference" "R471"
			(at 0.635 -2.32537 0)
			(unlocked yes)
			(layer "F.SilkS")
			(effects
				(font
					(size 0.7874 0.5842)
					(thickness 0.1524)
				)
			)
		)
		(property "Value" "VAL*"
			(at 0.02032 2.13233 180)
			(unlocked yes)
			(layer "F.Fab")
			(hide yes)
			(effects
				(font
					(size 0.7874 0.5842)
					(thickness 0.1524)
				)
			)
		)
		(property "Tolerance" "TOL*"
			(at 0.044704 3.05435 180)
			(unlocked yes)
			(layer "Cmts.User")
			(hide yes)
			(effects
				(font
					(size 0.7874 0.5842)
					(thickness 0.1524)
				)
			)
		)
		(property "User Part Number" "PARTNUM*"
			(at 0.02032 4.024884 180)
			(unlocked yes)
			(layer "Cmts.User")
			(hide yes)
			(effects
				(font
					(size 0.7874 0.5842)
					(thickness 0.1524)
				)
			)
		)
		(property "Device Type" "RESISTOR-G155-100R0-J0,0OHM,-"
			(at 0.008382 1.210564 180)
			(unlocked yes)
			(layer "F.Fab")
			(hide yes)
			(effects
				(font
					(size 0.7874 0.5842)
					(thickness 0.1524)
				)
			)
		)
		(duplicate_pad_numbers_are_jumpers no)
		(fp_line
			(start 1.143 0.5588)
			(end 1.143 -0.5588)
			(stroke
				(width 0.1)
				(type default)
			)
			(layer "F.SilkS")
		)
		(fp_line
			(start 1.143 -0.5588)
			(end -1.143 -0.5588)
			(stroke
				(width 0.1)
				(type default)
			)
			(layer "F.SilkS")
		)
		(fp_line
			(start -1.143 0.5588)
			(end 1.143 0.5588)
			(stroke
				(width 0.1)
				(type default)
			)
			(layer "F.SilkS")
		)
		(fp_line
			(start -1.143 -0.5588)
			(end -1.143 0.5588)
			(stroke
				(width 0.1)
				(type default)
			)
			(layer "F.SilkS")
		)
		(fp_poly
			(pts
				(xy -1.143 0.5588) (xy 1.143 0.5588) (xy 1.143 -0.5588) (xy -1.143 -0.5588)
			)
			(stroke
				(width 0)
				(type default)
			)
			(fill no)
			(layer "F.CrtYd")
		)
		(fp_line
			(start 0.508 0.3048)
			(end 0.508 -0.3048)
			(stroke
				(width 0.1)
				(type default)
			)
			(layer "F.Fab")
		)
		(fp_line
			(start 0.508 -0.3048)
			(end -0.508 -0.3048)
			(stroke
				(width 0.1)
				(type default)
			)
			(layer "F.Fab")
		)
		(fp_line
			(start -0.508 0.3048)
			(end 0.508 0.3048)
			(stroke
				(width 0.1)
				(type default)
			)
			(layer "F.Fab")
		)
		(fp_line
			(start -0.508 -0.3048)
			(end -0.508 0.3048)
			(stroke
				(width 0.1)
				(type default)
			)
			(layer "F.Fab")
		)
		(pad "1" smd rect
			(at -0.5334 0 180)
			(size 0.7112 0.6096)
			(layers "F.Cu" "F.Mask" "F.Paste")
			(net "R_FT4232_I2C_SCL")
		)
		(pad "2" smd rect
			(at 0.5334 0 180)
			(size 0.7112 0.6096)
			(layers "F.Cu" "F.Mask" "F.Paste")
			(net "FT4232_I2C_SCL")
		)
		(zone
			(layer "F.Cu")
			(hatch none 0.5)
			(connect_pads
				(clearance 0)
			)
			(min_thickness 0.25)
			(keepout
				(tracks not_allowed)
				(vias allowed)
				(pads allowed)
				(copperpour not_allowed)
				(footprints allowed)
			)
			(placement
				(enabled no)
				(sheetname "")
			)
			(fill
				(thermal_gap 0.5)
				(thermal_bridge_width 0.5)
				(island_removal_mode 0)
			)
			(polygon
				(pts
					(xy 18.4912 -82.7278) (xy 18.3388 -82.7278) (xy 18.3388 -82.1182) (xy 18.4912 -82.1182)
				)
			)
		)
		(zone
			(layer "F.Cu")
			(hatch none 0.5)
			(connect_pads
				(clearance 0)
			)
			(min_thickness 0.25)
			(keepout
				(tracks allowed)
				(vias not_allowed)
				(pads allowed)
				(copperpour not_allowed)
				(footprints allowed)
			)
			(placement
				(enabled no)
				(sheetname "")
			)
			(fill
				(thermal_gap 0.5)
				(thermal_bridge_width 0.5)
				(island_removal_mode 0)
			)
			(polygon
				(pts
					(xy 18.4912 -82.7278) (xy 18.3388 -82.7278) (xy 18.3388 -82.1182) (xy 18.4912 -82.1182)
				)
			)
		)
	)
	(footprint ""
		(layer "F.Cu")
		(at 106.807 -58.293)
		(property "Reference" "TP187"
			(at 3.20675 2.0828 90)
			(unlocked yes)
			(layer "F.SilkS")
			(effects
				(font
					(size 0.635 0.4064)
					(thickness 0.1524)
				)
				(justify left)
			)
		)
		(property "Value" ""
			(at 0 0 0)
			(layer "F.Fab")
			(effects
				(font
					(size 1.27 1.27)
				)
			)
		)
		(property "Device Type" "TP_PIONT-TP010CT020B030_PTH-TPA"
			(at -1.341882 0.996696 0)
			(unlocked yes)
			(layer "F.Fab")
			(hide yes)
			(effects
				(font
					(size 0.7874 0.5842)
					(thickness 0.1524)
				)
				(justify left)
			)
		)
		(duplicate_pad_numbers_are_jumpers no)
		(fp_poly
			(pts
				(arc
					(start 0.889 0)
					(mid -0.889 0)
					(end 0.889 0)
				)
			)
			(stroke
				(width 0)
				(type default)
			)
			(fill no)
			(layer "B.CrtYd")
		)
		(fp_poly
			(pts
				(arc
					(start 0.889 0)
					(mid -0.889 0)
					(end 0.889 0)
				)
			)
			(stroke
				(width 0)
				(type default)
			)
			(fill no)
			(layer "F.CrtYd")
		)
		(pad "1" thru_hole circle
			(at 0 0)
			(size 0.508 0.508)
			(drill 0.254)
			(layers "*.Cu" "*.Mask")
			(remove_unused_layers no)
			(net "IO_L24P_16")
			(clearance 0.1016)
			(padstack
				(mode front_inner_back)
				(layer "Inner"
					(shape circle)
					(size 0.508 0.508)
					(clearance 0.1016)
				)
				(layer "B.Cu"
					(shape circle)
					(size 0.762 0.762)
					(clearance -0.0254)
				)
			)
		)
	)
)
